(kicad_pcb
	(version 20260206)
	(generator "pcbnew")
	(generator_version "10.0")
	(general
		(thickness 1.6)
		(legacy_teardrops no)
	)
	(paper "A4")
	(title_block
		(title "03242023_DA0F0TMBIJ0_F0T_Motherboard_J_brd_V01_OCP.brd")
		(comment 1 "Grand Teton / footprint 3456 of 6105 (J35), pads 1-109 of 175")
	)
	(layers
		(0 "F.Cu" signal "TOP")
		(4 "In1.Cu" signal "GND")
		(6 "In2.Cu" signal "IN1")
		(8 "In3.Cu" signal "GND1")
		(10 "In4.Cu" signal "IN2")
		(12 "In5.Cu" signal "GND2")
		(14 "In6.Cu" signal "IN3")
		(16 "In7.Cu" signal "GND3")
		(18 "In8.Cu" signal "VCC")
		(20 "In9.Cu" signal "VCC1")
		(22 "In10.Cu" signal "GND4")
		(24 "In11.Cu" signal "IN4")
		(26 "In12.Cu" signal "GND5")
		(28 "In13.Cu" signal "IN5")
		(30 "In14.Cu" signal "GND6")
		(32 "In15.Cu" signal "IN6")
		(34 "In16.Cu" signal "GND7")
		(2 "B.Cu" signal "BOTTOM")
		(9 "F.Adhes" user "F.Adhesive")
		(11 "B.Adhes" user "B.Adhesive")
		(13 "F.Paste" user "Package Geometry/Pastemask Top")
		(15 "B.Paste" user "Package Geometry/Pastemask Bottom")
		(5 "F.SilkS" user "Ref Des/Silkscreen Top")
		(7 "B.SilkS" user "Ref Des/Silkscreen Bottom")
		(1 "F.Mask" user "Board Geometry/Soldermask Top")
		(3 "B.Mask" user "Board Geometry/Soldermask Bottom")
		(17 "Dwgs.User" user "User.Drawings")
		(19 "Cmts.User" user "User.Comments")
		(21 "Eco1.User" user "User.Eco1")
		(23 "Eco2.User" user "User.Eco2")
		(25 "Edge.Cuts" user "Board Geometry/Outline")
		(27 "Margin" user)
		(31 "F.CrtYd" user "Package Geometry/Place Bound Top")
		(29 "B.CrtYd" user "Package Geometry/Place Bound Bottom")
		(35 "F.Fab" user "Ref Des/Assembly Top")
		(33 "B.Fab" user "Ref Des/Assembly Bottom")
	)
	(footprint ""
		(layer "F.Cu")
		(at 47.401988 -5.569966 -90)
		(property "Reference" "J35"
			(at -16.848074 29.242004 0)
			(unlocked yes)
			(layer "F.SilkS")
			(effects
				(font
					(size 0.7874 0.5842)
					(thickness 0.1524)
				)
				(justify left)
			)
		)
		(property "Value" ""
			(at 0 0 270)
			(layer "F.Fab")
			(effects
				(font
					(size 1.27 1.27)
				)
			)
		)
		(duplicate_pad_numbers_are_jumpers no)
		(pad "" np_thru_hole circle
			(at -0.599948 -32.079946 180)
			(size 1.1176 1.1176)
			(drill 1.1176)
			(layers "*.Cu" "*.Mask")
			(clearance 0.381)
			(thermal_gap 0.381)
		)
		(pad "" np_thru_hole circle
			(at 0.40005 32.085026 180)
			(size 1.1176 1.1176)
			(drill 1.1176)
			(layers "*.Cu" "*.Mask")
			(clearance 0.381)
			(thermal_gap 0.381)
		)
		(pad "A1" smd rect
			(at -2.750058 -18.465038 180)
			(size 0.381 1.4478)
			(layers "F.Cu" "F.Mask" "F.Paste")
			(net "GND")
		)
		(pad "A2" smd rect
			(at -2.750058 -17.86509 180)
			(size 0.381 1.4478)
			(layers "F.Cu" "F.Mask" "F.Paste")
			(net "GND")
		)
		(pad "A3" smd rect
			(at -2.750058 -17.264888 180)
			(size 0.381 1.4478)
			(layers "F.Cu" "F.Mask" "F.Paste")
			(net "GND")
		)
		(pad "A4" smd rect
			(at -2.750058 -16.66494 180)
			(size 0.381 1.4478)
			(layers "F.Cu" "F.Mask" "F.Paste")
			(net "GND")
		)
		(pad "A5" smd rect
			(at -2.750058 -16.064992 180)
			(size 0.381 1.4478)
			(layers "F.Cu" "F.Mask" "F.Paste")
			(net "GND")
		)
		(pad "A6" smd rect
			(at -2.750058 -15.465044 180)
			(size 0.381 1.4478)
			(layers "F.Cu" "F.Mask" "F.Paste")
			(net "GND")
		)
		(pad "A7" smd rect
			(at -2.750058 -14.865096 180)
			(size 0.381 1.4478)
			(layers "F.Cu" "F.Mask" "F.Paste")
			(net "SMB_OCP_V3_2_3V3AUX_BUF_R_SCL")
		)
		(pad "A8" smd rect
			(at -2.750058 -14.264894 180)
			(size 0.381 1.4478)
			(layers "F.Cu" "F.Mask" "F.Paste")
			(net "SMB_OCP_V3_2_3V3AUX_BUF_R_SDA")
		)
		(pad "A9" smd rect
			(at -2.750058 -13.664946 180)
			(size 0.381 1.4478)
			(layers "F.Cu" "F.Mask" "F.Paste")
			(net "RST_SMB_OCP_V3_2_N")
		)
		(pad "A10" smd rect
			(at -2.750058 -13.064998 180)
			(size 0.381 1.4478)
			(layers "F.Cu" "F.Mask" "F.Paste")
			(net "OCP_V3_1_PRSNTA_R_N")
		)
		(pad "A11" smd rect
			(at -2.750058 -12.46505 180)
			(size 0.381 1.4478)
			(layers "F.Cu" "F.Mask" "F.Paste")
			(net "RST_PERST1_OCP_V3_2_N")
		)
		(pad "A12" smd rect
			(at -2.750058 -11.865102 180)
			(size 0.381 1.4478)
			(layers "F.Cu" "F.Mask" "F.Paste")
			(net "OCP_V3_2_PRSNT2_R_N")
		)
		(pad "A13" smd rect
			(at -2.750058 -11.2649 180)
			(size 0.381 1.4478)
			(layers "F.Cu" "F.Mask" "F.Paste")
			(net "GND")
		)
		(pad "A14" smd rect
			(at -2.750058 -10.664952 180)
			(size 0.381 1.4478)
			(layers "F.Cu" "F.Mask" "F.Paste")
			(net "CLK_100M_OCP_V3_2_B_DN")
		)
		(pad "A15" smd rect
			(at -2.750058 -10.065004 180)
			(size 0.381 1.4478)
			(layers "F.Cu" "F.Mask" "F.Paste")
			(net "CLK_100M_OCP_V3_2_B_DP")
		)
		(pad "A16" smd rect
			(at -2.750058 -9.465056 180)
			(size 0.381 1.4478)
			(layers "F.Cu" "F.Mask" "F.Paste")
			(net "GND")
		)
		(pad "A17" smd rect
			(at -2.750058 -8.865108 180)
			(size 0.381 1.4478)
			(layers "F.Cu" "F.Mask" "F.Paste")
			(net "P5E_CPU1_PE1_RX_DN<0>")
		)
		(pad "A18" smd rect
			(at -2.750058 -8.264906 180)
			(size 0.381 1.4478)
			(layers "F.Cu" "F.Mask" "F.Paste")
			(net "P5E_CPU1_PE1_RX_DP<0>")
		)
		(pad "A19" smd rect
			(at -2.750058 -7.664958 180)
			(size 0.381 1.4478)
			(layers "F.Cu" "F.Mask" "F.Paste")
			(net "GND")
		)
		(pad "A20" smd rect
			(at -2.750058 -7.06501 180)
			(size 0.381 1.4478)
			(layers "F.Cu" "F.Mask" "F.Paste")
			(net "P5E_CPU1_PE1_RX_DN<1>")
		)
		(pad "A21" smd rect
			(at -2.750058 -6.465062 180)
			(size 0.381 1.4478)
			(layers "F.Cu" "F.Mask" "F.Paste")
			(net "P5E_CPU1_PE1_RX_DP<1>")
		)
		(pad "A22" smd rect
			(at -2.750058 -5.865114 180)
			(size 0.381 1.4478)
			(layers "F.Cu" "F.Mask" "F.Paste")
			(net "GND")
		)
		(pad "A23" smd rect
			(at -2.750058 -5.264912 180)
			(size 0.381 1.4478)
			(layers "F.Cu" "F.Mask" "F.Paste")
			(net "P5E_CPU1_PE1_RX_DN<2>")
		)
		(pad "A24" smd rect
			(at -2.750058 -4.664964 180)
			(size 0.381 1.4478)
			(layers "F.Cu" "F.Mask" "F.Paste")
			(net "P5E_CPU1_PE1_RX_DP<2>")
		)
		(pad "A25" smd rect
			(at -2.750058 -4.065016 180)
			(size 0.381 1.4478)
			(layers "F.Cu" "F.Mask" "F.Paste")
			(net "GND")
		)
		(pad "A26" smd rect
			(at -2.750058 -3.465068 180)
			(size 0.381 1.4478)
			(layers "F.Cu" "F.Mask" "F.Paste")
			(net "P5E_CPU1_PE1_RX_DN<3>")
		)
		(pad "A27" smd rect
			(at -2.750058 -2.86512 180)
			(size 0.381 1.4478)
			(layers "F.Cu" "F.Mask" "F.Paste")
			(net "P5E_CPU1_PE1_RX_DP<3>")
		)
		(pad "A28" smd rect
			(at -2.750058 -2.264918 180)
			(size 0.381 1.4478)
			(layers "F.Cu" "F.Mask" "F.Paste")
			(net "GND")
		)
		(pad "A29" smd rect
			(at -2.750058 1.74498 180)
			(size 0.381 1.4478)
			(layers "F.Cu" "F.Mask" "F.Paste")
			(net "GND")
		)
		(pad "A30" smd rect
			(at -2.750058 2.344928 180)
			(size 0.381 1.4478)
			(layers "F.Cu" "F.Mask" "F.Paste")
			(net "P5E_CPU1_PE1_RX_DN<4>")
		)
		(pad "A31" smd rect
			(at -2.750058 2.944876 180)
			(size 0.381 1.4478)
			(layers "F.Cu" "F.Mask" "F.Paste")
			(net "P5E_CPU1_PE1_RX_DP<4>")
		)
		(pad "A32" smd rect
			(at -2.750058 3.545078 180)
			(size 0.381 1.4478)
			(layers "F.Cu" "F.Mask" "F.Paste")
			(net "GND")
		)
		(pad "A33" smd rect
			(at -2.750058 4.145026 180)
			(size 0.381 1.4478)
			(layers "F.Cu" "F.Mask" "F.Paste")
			(net "P5E_CPU1_PE1_RX_DN<5>")
		)
		(pad "A34" smd rect
			(at -2.750058 4.744974 180)
			(size 0.381 1.4478)
			(layers "F.Cu" "F.Mask" "F.Paste")
			(net "P5E_CPU1_PE1_RX_DP<5>")
		)
		(pad "A35" smd rect
			(at -2.750058 5.344922 180)
			(size 0.381 1.4478)
			(layers "F.Cu" "F.Mask" "F.Paste")
			(net "GND")
		)
		(pad "A36" smd rect
			(at -2.750058 5.945124 180)
			(size 0.381 1.4478)
			(layers "F.Cu" "F.Mask" "F.Paste")
			(net "P5E_CPU1_PE1_RX_DN<6>")
		)
		(pad "A37" smd rect
			(at -2.750058 6.545072 180)
			(size 0.381 1.4478)
			(layers "F.Cu" "F.Mask" "F.Paste")
			(net "P5E_CPU1_PE1_RX_DP<6>")
		)
		(pad "A38" smd rect
			(at -2.750058 7.14502 180)
			(size 0.381 1.4478)
			(layers "F.Cu" "F.Mask" "F.Paste")
			(net "GND")
		)
		(pad "A39" smd rect
			(at -2.750058 7.744968 180)
			(size 0.381 1.4478)
			(layers "F.Cu" "F.Mask" "F.Paste")
			(net "P5E_CPU1_PE1_RX_DN<7>")
		)
		(pad "A40" smd rect
			(at -2.750058 8.344916 180)
			(size 0.381 1.4478)
			(layers "F.Cu" "F.Mask" "F.Paste")
			(net "P5E_CPU1_PE1_RX_DP<7>")
		)
		(pad "A41" smd rect
			(at -2.750058 8.945118 180)
			(size 0.381 1.4478)
			(layers "F.Cu" "F.Mask" "F.Paste")
			(net "GND")
		)
		(pad "A42" smd rect
			(at -2.750058 9.545066 180)
			(size 0.381 1.4478)
			(layers "F.Cu" "F.Mask" "F.Paste")
			(net "OCP_V3_2_PRSNT1_R_N")
		)
		(pad "A43" smd rect
			(at -2.750058 14.454886 180)
			(size 0.381 1.4478)
			(layers "F.Cu" "F.Mask" "F.Paste")
			(net "GND")
		)
		(pad "A44" smd rect
			(at -2.750058 15.055088 180)
			(size 0.381 1.4478)
			(layers "F.Cu" "F.Mask" "F.Paste")
			(net "P5E_CPU1_PE1_RX_DN<8>")
		)
		(pad "A45" smd rect
			(at -2.750058 15.655036 180)
			(size 0.381 1.4478)
			(layers "F.Cu" "F.Mask" "F.Paste")
			(net "P5E_CPU1_PE1_RX_DP<8>")
		)
		(pad "A46" smd rect
			(at -2.750058 16.254984 180)
			(size 0.381 1.4478)
			(layers "F.Cu" "F.Mask" "F.Paste")
			(net "GND")
		)
		(pad "A47" smd rect
			(at -2.750058 16.854932 180)
			(size 0.381 1.4478)
			(layers "F.Cu" "F.Mask" "F.Paste")
			(net "P5E_CPU1_PE1_RX_DN<9>")
		)
		(pad "A48" smd rect
			(at -2.750058 17.45488 180)
			(size 0.381 1.4478)
			(layers "F.Cu" "F.Mask" "F.Paste")
			(net "P5E_CPU1_PE1_RX_DP<9>")
		)
		(pad "A49" smd rect
			(at -2.750058 18.055082 180)
			(size 0.381 1.4478)
			(layers "F.Cu" "F.Mask" "F.Paste")
			(net "GND")
		)
		(pad "A50" smd rect
			(at -2.750058 18.65503 180)
			(size 0.381 1.4478)
			(layers "F.Cu" "F.Mask" "F.Paste")
			(net "P5E_CPU1_PE1_RX_DN<10>")
		)
		(pad "A51" smd rect
			(at -2.750058 19.254978 180)
			(size 0.381 1.4478)
			(layers "F.Cu" "F.Mask" "F.Paste")
			(net "P5E_CPU1_PE1_RX_DP<10>")
		)
		(pad "A52" smd rect
			(at -2.750058 19.854926 180)
			(size 0.381 1.4478)
			(layers "F.Cu" "F.Mask" "F.Paste")
			(net "GND")
		)
		(pad "A53" smd rect
			(at -2.750058 20.455128 180)
			(size 0.381 1.4478)
			(layers "F.Cu" "F.Mask" "F.Paste")
			(net "P5E_CPU1_PE1_RX_DN<11>")
		)
		(pad "A54" smd rect
			(at -2.750058 21.055076 180)
			(size 0.381 1.4478)
			(layers "F.Cu" "F.Mask" "F.Paste")
			(net "P5E_CPU1_PE1_RX_DP<11>")
		)
		(pad "A55" smd rect
			(at -2.750058 21.655024 180)
			(size 0.381 1.4478)
			(layers "F.Cu" "F.Mask" "F.Paste")
			(net "GND")
		)
		(pad "A56" smd rect
			(at -2.750058 22.254972 180)
			(size 0.381 1.4478)
			(layers "F.Cu" "F.Mask" "F.Paste")
			(net "P5E_CPU1_PE1_RX_DN<12>")
		)
		(pad "A57" smd rect
			(at -2.750058 22.85492 180)
			(size 0.381 1.4478)
			(layers "F.Cu" "F.Mask" "F.Paste")
			(net "P5E_CPU1_PE1_RX_DP<12>")
		)
		(pad "A58" smd rect
			(at -2.750058 23.455122 180)
			(size 0.381 1.4478)
			(layers "F.Cu" "F.Mask" "F.Paste")
			(net "GND")
		)
		(pad "A59" smd rect
			(at -2.750058 24.05507 180)
			(size 0.381 1.4478)
			(layers "F.Cu" "F.Mask" "F.Paste")
			(net "P5E_CPU1_PE1_RX_DN<13>")
		)
		(pad "A60" smd rect
			(at -2.750058 24.655018 180)
			(size 0.381 1.4478)
			(layers "F.Cu" "F.Mask" "F.Paste")
			(net "P5E_CPU1_PE1_RX_DP<13>")
		)
		(pad "A61" smd rect
			(at -2.750058 25.254966 180)
			(size 0.381 1.4478)
			(layers "F.Cu" "F.Mask" "F.Paste")
			(net "GND")
		)
		(pad "A62" smd rect
			(at -2.750058 25.854914 180)
			(size 0.381 1.4478)
			(layers "F.Cu" "F.Mask" "F.Paste")
			(net "P5E_CPU1_PE1_RX_DN<14>")
		)
		(pad "A63" smd rect
			(at -2.750058 26.455116 180)
			(size 0.381 1.4478)
			(layers "F.Cu" "F.Mask" "F.Paste")
			(net "P5E_CPU1_PE1_RX_DP<14>")
		)
		(pad "A64" smd rect
			(at -2.750058 27.055064 180)
			(size 0.381 1.4478)
			(layers "F.Cu" "F.Mask" "F.Paste")
			(net "GND")
		)
		(pad "A65" smd rect
			(at -2.750058 27.655012 180)
			(size 0.381 1.4478)
			(layers "F.Cu" "F.Mask" "F.Paste")
			(net "P5E_CPU1_PE1_RX_DN<15>")
		)
		(pad "A66" smd rect
			(at -2.750058 28.25496 180)
			(size 0.381 1.4478)
			(layers "F.Cu" "F.Mask" "F.Paste")
			(net "P5E_CPU1_PE1_RX_DP<15>")
		)
		(pad "A67" smd rect
			(at -2.750058 28.854908 180)
			(size 0.381 1.4478)
			(layers "F.Cu" "F.Mask" "F.Paste")
			(net "GND")
		)
		(pad "A68" smd rect
			(at -2.750058 29.45511 180)
			(size 0.381 1.4478)
			(layers "F.Cu" "F.Mask" "F.Paste")
			(net "USB2_5_R1_DN")
		)
		(pad "A69" smd rect
			(at -2.750058 30.055058 180)
			(size 0.381 1.4478)
			(layers "F.Cu" "F.Mask" "F.Paste")
			(net "USB2_5_R1_DP")
		)
		(pad "A70" smd rect
			(at -2.750058 30.655006 180)
			(size 0.381 1.4478)
			(layers "F.Cu" "F.Mask" "F.Paste")
			(net "OCP_V3_2_PWRBRK_N")
		)
		(pad "B1" smd rect
			(at -5.700014 -18.465038 180)
			(size 0.381 1.4478)
			(layers "F.Cu" "F.Mask" "F.Paste")
			(net "P12V_OCP_V3_2")
		)
		(pad "B2" smd rect
			(at -5.700014 -17.86509 180)
			(size 0.381 1.4478)
			(layers "F.Cu" "F.Mask" "F.Paste")
			(net "P12V_OCP_V3_2")
		)
		(pad "B3" smd rect
			(at -5.700014 -17.264888 180)
			(size 0.381 1.4478)
			(layers "F.Cu" "F.Mask" "F.Paste")
			(net "P12V_OCP_V3_2")
		)
		(pad "B4" smd rect
			(at -5.700014 -16.66494 180)
			(size 0.381 1.4478)
			(layers "F.Cu" "F.Mask" "F.Paste")
			(net "P12V_OCP_V3_2")
		)
		(pad "B5" smd rect
			(at -5.700014 -16.064992 180)
			(size 0.381 1.4478)
			(layers "F.Cu" "F.Mask" "F.Paste")
			(net "P12V_OCP_V3_2")
		)
		(pad "B6" smd rect
			(at -5.700014 -15.465044 180)
			(size 0.381 1.4478)
			(layers "F.Cu" "F.Mask" "F.Paste")
			(net "P12V_OCP_V3_2")
		)
		(pad "B7" smd rect
			(at -5.700014 -14.865096 180)
			(size 0.381 1.4478)
			(layers "F.Cu" "F.Mask" "F.Paste")
			(net "OCP_V3_2_BIF0_R_N")
		)
		(pad "B8" smd rect
			(at -5.700014 -14.264894 180)
			(size 0.381 1.4478)
			(layers "F.Cu" "F.Mask" "F.Paste")
			(net "OCP_V3_2_BIF1_R_N")
		)
		(pad "B9" smd rect
			(at -5.700014 -13.664946 180)
			(size 0.381 1.4478)
			(layers "F.Cu" "F.Mask" "F.Paste")
			(net "OCP_V3_2_BIF2_R_N")
		)
		(pad "B10" smd rect
			(at -5.700014 -13.064998 180)
			(size 0.381 1.4478)
			(layers "F.Cu" "F.Mask" "F.Paste")
			(net "RST_PERST0_OCP_V3_2_N")
		)
		(pad "B11" smd rect
			(at -5.700014 -12.46505 180)
			(size 0.381 1.4478)
			(layers "F.Cu" "F.Mask" "F.Paste")
			(net "P3V3_OCP_V3_2")
		)
		(pad "B12" smd rect
			(at -5.700014 -11.865102 180)
			(size 0.381 1.4478)
			(layers "F.Cu" "F.Mask" "F.Paste")
			(net "OCP_V3_2_AUX_PWR_EN_R")
		)
		(pad "B13" smd rect
			(at -5.700014 -11.2649 180)
			(size 0.381 1.4478)
			(layers "F.Cu" "F.Mask" "F.Paste")
			(net "GND")
		)
		(pad "B14" smd rect
			(at -5.700014 -10.664952 180)
			(size 0.381 1.4478)
			(layers "F.Cu" "F.Mask" "F.Paste")
			(net "CLK_100M_OCP_V3_2_A_DN")
		)
		(pad "B15" smd rect
			(at -5.700014 -10.065004 180)
			(size 0.381 1.4478)
			(layers "F.Cu" "F.Mask" "F.Paste")
			(net "CLK_100M_OCP_V3_2_A_DP")
		)
		(pad "B16" smd rect
			(at -5.700014 -9.465056 180)
			(size 0.381 1.4478)
			(layers "F.Cu" "F.Mask" "F.Paste")
			(net "GND")
		)
		(pad "B17" smd rect
			(at -5.700014 -8.865108 180)
			(size 0.381 1.4478)
			(layers "F.Cu" "F.Mask" "F.Paste")
			(net "P5E_CPU1_PE1_TX_C_DP<0>")
		)
		(pad "B18" smd rect
			(at -5.700014 -8.264906 180)
			(size 0.381 1.4478)
			(layers "F.Cu" "F.Mask" "F.Paste")
			(net "P5E_CPU1_PE1_TX_C_DN<0>")
		)
		(pad "B19" smd rect
			(at -5.700014 -7.664958 180)
			(size 0.381 1.4478)
			(layers "F.Cu" "F.Mask" "F.Paste")
			(net "GND")
		)
		(pad "B20" smd rect
			(at -5.700014 -7.06501 180)
			(size 0.381 1.4478)
			(layers "F.Cu" "F.Mask" "F.Paste")
			(net "P5E_CPU1_PE1_TX_C_DN<1>")
		)
		(pad "B21" smd rect
			(at -5.700014 -6.465062 180)
			(size 0.381 1.4478)
			(layers "F.Cu" "F.Mask" "F.Paste")
			(net "P5E_CPU1_PE1_TX_C_DP<1>")
		)
		(pad "B22" smd rect
			(at -5.700014 -5.865114 180)
			(size 0.381 1.4478)
			(layers "F.Cu" "F.Mask" "F.Paste")
			(net "GND")
		)
		(pad "B23" smd rect
			(at -5.700014 -5.264912 180)
			(size 0.381 1.4478)
			(layers "F.Cu" "F.Mask" "F.Paste")
			(net "P5E_CPU1_PE1_TX_C_DP<2>")
		)
		(pad "B24" smd rect
			(at -5.700014 -4.664964 180)
			(size 0.381 1.4478)
			(layers "F.Cu" "F.Mask" "F.Paste")
			(net "P5E_CPU1_PE1_TX_C_DN<2>")
		)
		(pad "B25" smd rect
			(at -5.700014 -4.065016 180)
			(size 0.381 1.4478)
			(layers "F.Cu" "F.Mask" "F.Paste")
			(net "GND")
		)
		(pad "B26" smd rect
			(at -5.700014 -3.465068 180)
			(size 0.381 1.4478)
			(layers "F.Cu" "F.Mask" "F.Paste")
			(net "P5E_CPU1_PE1_TX_C_DN<3>")
		)
		(pad "B27" smd rect
			(at -5.700014 -2.86512 180)
			(size 0.381 1.4478)
			(layers "F.Cu" "F.Mask" "F.Paste")
			(net "P5E_CPU1_PE1_TX_C_DP<3>")
		)
		(pad "B28" smd rect
			(at -5.700014 -2.264918 180)
			(size 0.381 1.4478)
			(layers "F.Cu" "F.Mask" "F.Paste")
			(net "GND")
		)
		(pad "B29" smd rect
			(at -5.700014 1.74498 180)
			(size 0.381 1.4478)
			(layers "F.Cu" "F.Mask" "F.Paste")
			(net "GND")
		)
		(pad "B30" smd rect
			(at -5.700014 2.344928 180)
			(size 0.381 1.4478)
			(layers "F.Cu" "F.Mask" "F.Paste")
			(net "P5E_CPU1_PE1_TX_C_DP<4>")
		)
		(pad "B31" smd rect
			(at -5.700014 2.944876 180)
			(size 0.381 1.4478)
			(layers "F.Cu" "F.Mask" "F.Paste")
			(net "P5E_CPU1_PE1_TX_C_DN<4>")
		)
		(pad "B32" smd rect
			(at -5.700014 3.545078 180)
			(size 0.381 1.4478)
			(layers "F.Cu" "F.Mask" "F.Paste")
			(net "GND")
		)
		(pad "B33" smd rect
			(at -5.700014 4.145026 180)
			(size 0.381 1.4478)
			(layers "F.Cu" "F.Mask" "F.Paste")
			(net "P5E_CPU1_PE1_TX_C_DN<5>")
		)
		(pad "B34" smd rect
			(at -5.700014 4.744974 180)
			(size 0.381 1.4478)
			(layers "F.Cu" "F.Mask" "F.Paste")
			(net "P5E_CPU1_PE1_TX_C_DP<5>")
		)
		(pad "B35" smd rect
			(at -5.700014 5.344922 180)
			(size 0.381 1.4478)
			(layers "F.Cu" "F.Mask" "F.Paste")
			(net "GND")
		)
		(pad "B36" smd rect
			(at -5.700014 5.945124 180)
			(size 0.381 1.4478)
			(layers "F.Cu" "F.Mask" "F.Paste")
			(net "P5E_CPU1_PE1_TX_C_DP<6>")
		)
		(pad "B37" smd rect
			(at -5.700014 6.545072 180)
			(size 0.381 1.4478)
			(layers "F.Cu" "F.Mask" "F.Paste")
			(net "P5E_CPU1_PE1_TX_C_DN<6>")
		)
	)
)
